# SCM (Grand Teton) — schematic netlist excerpt (pin names and nets, part order shuffled) for the footprints in the layout excerpt that follows; sources: Cadence DE-HDL packaged netlist, KiCad conversion of 12092022_DA0F0TMDCD0_F0T_Management_Board_D_brd_V3_OCP.brd

R171  Q_RES  22 1% CHIP  pkg 0402LF  page 13 : A = RMII_TXEN_R ; B = RMII_TXEN
R379  Q_RES  0 5% CHIP  pkg 0402LF  page 36 : A = PWRGD_P1V0_AUX_R1 ; B = PWRGD_P1V0_AUX

(kicad_pcb
	(version 20260206)
	(generator "pcbnew")
	(generator_version "10.0")
	(general
		(thickness 1.6)
		(legacy_teardrops no)
	)
	(paper "A4")
	(title_block
		(title "12092022_DA0F0TMDCD0_F0T_Management_Board_D_brd_V3_OCP.brd")
		(comment 1 "Grand Teton / footprints 1107-1108 of 1440")
	)
	(layers
		(0 "F.Cu" signal "TOP")
		(4 "In1.Cu" signal "GND")
		(6 "In2.Cu" signal "IN1")
		(8 "In3.Cu" signal "GND1")
		(10 "In4.Cu" signal "IN2")
		(12 "In5.Cu" signal "VCC")
		(14 "In6.Cu" signal "VCC1")
		(16 "In7.Cu" signal "IN3")
		(18 "In8.Cu" signal "GND2")
		(20 "In9.Cu" signal "IN4")
		(22 "In10.Cu" signal "GND3")
		(2 "B.Cu" signal "BOTTOM")
		(9 "F.Adhes" user "F.Adhesive")
		(11 "B.Adhes" user "B.Adhesive")
		(13 "F.Paste" user "Package Geometry/Pastemask Top")
		(15 "B.Paste" user "Package Geometry/Pastemask Bottom")
		(5 "F.SilkS" user "Ref Des/Silkscreen Top")
		(7 "B.SilkS" user "Ref Des/Silkscreen Bottom")
		(1 "F.Mask" user "Board Geometry/Soldermask Top")
		(3 "B.Mask" user "Board Geometry/Soldermask Bottom")
		(17 "Dwgs.User" user "User.Drawings")
		(19 "Cmts.User" user "User.Comments")
		(21 "Eco1.User" user "User.Eco1")
		(23 "Eco2.User" user "User.Eco2")
		(25 "Edge.Cuts" user "Board Geometry/Outline")
		(27 "Margin" user)
		(31 "F.CrtYd" user "Package Geometry/Place Bound Top")
		(29 "B.CrtYd" user "Package Geometry/Place Bound Bottom")
		(35 "F.Fab" user "Ref Des/Assembly Top")
		(33 "B.Fab" user "Ref Des/Assembly Bottom")
	)
	(footprint ""
		(layer "B.Cu")
		(at 17.907 -101.981 -90)
		(property "Reference" "R379"
			(at 0 0 90)
			(layer "B.SilkS")
			(hide yes)
			(effects
				(font
					(size 1.27 1.27)
				)
				(justify mirror)
			)
		)
		(property "Value" ""
			(at 0 0 90)
			(layer "B.Fab")
			(effects
				(font
					(size 1.27 1.27)
				)
				(justify mirror)
			)
		)
		(duplicate_pad_numbers_are_jumpers no)
		(fp_line
			(start -0.7874 0.4064)
			(end 0.7874 0.4064)
			(stroke
				(width 0.1524)
				(type default)
			)
			(layer "B.SilkS")
		)
		(fp_line
			(start 0.7874 0.4064)
			(end 0.7874 -0.4064)
			(stroke
				(width 0.1524)
				(type default)
			)
			(layer "B.SilkS")
		)
		(fp_line
			(start -0.7874 -0.4064)
			(end -0.7874 0.4064)
			(stroke
				(width 0.1524)
				(type default)
			)
			(layer "B.SilkS")
		)
		(fp_line
			(start 0.7874 -0.4064)
			(end -0.7874 -0.4064)
			(stroke
				(width 0.1524)
				(type default)
			)
			(layer "B.SilkS")
		)
		(fp_line
			(start -0.67945 0.3048)
			(end -0.120396 0.3048)
			(stroke
				(width 0.1)
				(type default)
			)
			(layer "B.Fab")
		)
		(fp_line
			(start -0.120396 0.3048)
			(end -0.120396 0.2794)
			(stroke
				(width 0.1)
				(type default)
			)
			(layer "B.Fab")
		)
		(fp_line
			(start 0.12065 0.3048)
			(end 0.67945 0.3048)
			(stroke
				(width 0.1)
				(type default)
			)
			(layer "B.Fab")
		)
		(fp_line
			(start 0.67945 0.3048)
			(end 0.67945 -0.305054)
			(stroke
				(width 0.1)
				(type default)
			)
			(layer "B.Fab")
		)
		(fp_line
			(start -0.120396 0.2794)
			(end 0.12065 0.2794)
			(stroke
				(width 0.1)
				(type default)
			)
			(layer "B.Fab")
		)
		(fp_line
			(start 0.12065 0.2794)
			(end 0.12065 0.3048)
			(stroke
				(width 0.1)
				(type default)
			)
			(layer "B.Fab")
		)
		(fp_line
			(start -0.12065 -0.2794)
			(end -0.12065 -0.3048)
			(stroke
				(width 0.1)
				(type default)
			)
			(layer "B.Fab")
		)
		(fp_line
			(start 0.12065 -0.2794)
			(end -0.12065 -0.2794)
			(stroke
				(width 0.1)
				(type default)
			)
			(layer "B.Fab")
		)
		(fp_line
			(start -0.67945 -0.3048)
			(end -0.67945 0.3048)
			(stroke
				(width 0.1)
				(type default)
			)
			(layer "B.Fab")
		)
		(fp_line
			(start -0.12065 -0.3048)
			(end -0.67945 -0.3048)
			(stroke
				(width 0.1)
				(type default)
			)
			(layer "B.Fab")
		)
		(fp_line
			(start 0.12065 -0.305054)
			(end 0.12065 -0.2794)
			(stroke
				(width 0.1)
				(type default)
			)
			(layer "B.Fab")
		)
		(fp_line
			(start 0.67945 -0.305054)
			(end 0.12065 -0.305054)
			(stroke
				(width 0.1)
				(type default)
			)
			(layer "B.Fab")
		)
		(pad "1" smd circle
			(at 0.40005 0 90)
			(size 0 0)
			(layers "B.Cu" "B.Mask" "B.Paste")
			(net "PWRGD_P1V0_AUX_R1")
		)
		(pad "2" smd circle
			(at -0.40005 0 90)
			(size 0 0)
			(layers "B.Cu" "B.Mask" "B.Paste")
			(net "PWRGD_P1V0_AUX")
		)
	)
	(footprint ""
		(layer "B.Cu")
		(at 42.220134 -39.95166)
		(property "Reference" "R171"
			(at 0 0 0)
			(layer "B.SilkS")
			(hide yes)
			(effects
				(font
					(size 1.27 1.27)
				)
				(justify mirror)
			)
		)
		(property "Value" ""
			(at 0 0 0)
			(layer "B.Fab")
			(effects
				(font
					(size 1.27 1.27)
				)
				(justify mirror)
			)
		)
		(duplicate_pad_numbers_are_jumpers no)
		(fp_line
			(start -0.7874 -0.4064)
			(end -0.7874 0.4064)
			(stroke
				(width 0.1524)
				(type default)
			)
			(layer "B.SilkS")
		)
		(fp_line
			(start -0.7874 0.4064)
			(end 0.7874 0.4064)
			(stroke
				(width 0.1524)
				(type default)
			)
			(layer "B.SilkS")
		)
		(fp_line
			(start 0.7874 -0.4064)
			(end -0.7874 -0.4064)
			(stroke
				(width 0.1524)
				(type default)
			)
			(layer "B.SilkS")
		)
		(fp_line
			(start 0.7874 0.4064)
			(end 0.7874 -0.4064)
			(stroke
				(width 0.1524)
				(type default)
			)
			(layer "B.SilkS")
		)
		(fp_line
			(start -0.67945 -0.3048)
			(end -0.67945 0.3048)
			(stroke
				(width 0.1)
				(type default)
			)
			(layer "B.Fab")
		)
		(fp_line
			(start -0.67945 0.3048)
			(end -0.120396 0.3048)
			(stroke
				(width 0.1)
				(type default)
			)
			(layer "B.Fab")
		)
		(fp_line
			(start -0.12065 -0.3048)
			(end -0.67945 -0.3048)
			(stroke
				(width 0.1)
				(type default)
			)
			(layer "B.Fab")
		)
		(fp_line
			(start -0.12065 -0.2794)
			(end -0.12065 -0.3048)
			(stroke
				(width 0.1)
				(type default)
			)
			(layer "B.Fab")
		)
		(fp_line
			(start -0.120396 0.2794)
			(end 0.12065 0.2794)
			(stroke
				(width 0.1)
				(type default)
			)
			(layer "B.Fab")
		)
		(fp_line
			(start -0.120396 0.3048)
			(end -0.120396 0.2794)
			(stroke
				(width 0.1)
				(type default)
			)
			(layer "B.Fab")
		)
		(fp_line
			(start 0.12065 -0.305054)
			(end 0.12065 -0.2794)
			(stroke
				(width 0.1)
				(type default)
			)
			(layer "B.Fab")
		)
		(fp_line
			(start 0.12065 -0.2794)
			(end -0.12065 -0.2794)
			(stroke
				(width 0.1)
				(type default)
			)
			(layer "B.Fab")
		)
		(fp_line
			(start 0.12065 0.2794)
			(end 0.12065 0.3048)
			(stroke
				(width 0.1)
				(type default)
			)
			(layer "B.Fab")
		)
		(fp_line
			(start 0.12065 0.3048)
			(end 0.67945 0.3048)
			(stroke
				(width 0.1)
				(type default)
			)
			(layer "B.Fab")
		)
		(fp_line
			(start 0.67945 -0.305054)
			(end 0.12065 -0.305054)
			(stroke
				(width 0.1)
				(type default)
			)
			(layer "B.Fab")
		)
		(fp_line
			(start 0.67945 0.3048)
			(end 0.67945 -0.305054)
			(stroke
				(width 0.1)
				(type default)
			)
			(layer "B.Fab")
		)
		(pad "1" smd circle
			(at 0.40005 0 180)
			(size 0 0)
			(layers "B.Cu" "B.Mask" "B.Paste")
			(net "RMII_TXEN_R")
		)
		(pad "2" smd circle
			(at -0.40005 0 180)
			(size 0 0)
			(layers "B.Cu" "B.Mask" "B.Paste")
			(net "RMII_TXEN")
		)
	)
)
